FILE_TYPE = CONNECTIVITY;
{Allegro Design Entry HDL 17.4-2019 S026 (4007227) 1/17/2022}
"PAGE_NUMBER" = 411;
0"NC";
1"P1V8_CPU0_RT1_1A\g";
2"P0V9_CPU0_RT1_2A\g";
3"GND\g";
4"P0V9_CPU0_RT_2D\g";
5"GND\g";
6"P1V8_CPU0_RT_1D\g";
7"GND\g";
8"GND\g";
9"GND\g";
10"P1V8_CPU0_RT1_1A_1D\g";
11"GND\g";
12"GND\g";
13"P0V9_CPU0_RT1_2A_2D\g";
%"Q_RES"
"2","(-4475,2475)","2","pure_quanta","I10";
;
LOCATION"R1010"
$SEC"1"
CDS_SEC"1"
TOLERANCE"5%"
VALUE"0"
PACK_TYPE"0603LF"
WATTAGE"1/4W"
MATERIAL"EMPTY"
CDS_LIB"pure_quanta"
PART_NUMBER"CS00006J900";
"A"
$PN"1"4;
"B"
$PN"2"13;
%"Q_INDUCTOR"
"1","(-7950,4175)","0","pure_quanta","I11";
;
LOCATION"L13"
$SEC"1"
CDS_SEC"1"
MATERIAL"IND"
PACK_TYPE"SMLF"
VALUE"BLM21SN300SN1D/5A"
NEEDS_NO_SIZE"TRUE"
CDS_LIB"pure_quanta"
PART_NUMBER"CX300SN1000";
"1"
$PN"1"6;
"2"
$PN"2"1;
%"Q_CAP"
"1","(-7375,3900)","0","pure_quanta","I12";
;
LOCATION"C588"
$SEC"1"
CDS_SEC"1"
VOLTAGE"4V"
PACK_TYPE"C0805"
VALUE"100UF"
MATERIAL"X6S"
TOLERANCE"20%"
CDS_LIB"pure_quanta"
PART_NUMBER"CH710KMEA01";
"B"
$PN"2"8;
"A"
$PN"1"1;
%"P1V0"
"1","(-7475,4375)","0","pure_quanta_power","I13";
;
HDL_POWER"P1V8_CPU0_RT1_1A"
CDS_LIB"pure_quanta_power";
"A"1;
%"P1V0"
"1","(-8325,5000)","0","pure_quanta_power","I14";
;
HDL_POWER"P1V8_CPU0_RT_1D"
CDS_LIB"pure_quanta_power";
"A"6;
%"Q_CAP"
"1","(-7150,3900)","0","pure_quanta","I15";
;
LOCATION"C590"
$SEC"1"
CDS_SEC"1"
VOLTAGE"4V"
VALUE"22UF"
MATERIAL"X6S"
TOLERANCE"20%"
PACK_TYPE"C0402"
CDS_LIB"pure_quanta"
PART_NUMBER"CH622KMEB02";
"B"
$PN"2"8;
"A"
$PN"1"1;
%"Q_CAP"
"1","(-6950,3900)","0","pure_quanta","I16";
;
LOCATION"C595"
$SEC"1"
CDS_SEC"1"
VOLTAGE"6.3V"
VALUE"10UF"
TOLERANCE"20%"
MATERIAL"X6S"
PACK_TYPE"C0402"
CDS_LIB"pure_quanta"
PART_NUMBER"CH6101MEB01";
"B"
$PN"2"8;
"A"
$PN"1"1;
%"Q_CAP"
"1","(-7225,4725)","0","pure_quanta","I17";
;
LOCATION"C587"
$SEC"1"
CDS_SEC"1"
VALUE"100UF"
VOLTAGE"4V"
TOLERANCE"20%"
MATERIAL"X6S"
PACK_TYPE"C0805"
CDS_LIB"pure_quanta"
PART_NUMBER"CH710KMEA01";
"B"
$PN"2"7;
"A"
$PN"1"6;
%"Q_CAP"
"1","(-6975,4725)","0","pure_quanta","I18";
;
LOCATION"C589"
$SEC"1"
CDS_SEC"1"
TOLERANCE"20%"
PACK_TYPE"C0402"
MATERIAL"X6S"
VALUE"22UF"
VOLTAGE"4V"
CDS_LIB"pure_quanta"
PART_NUMBER"CH622KMEB02";
"B"
$PN"2"7;
"A"
$PN"1"6;
%"Q_CAP"
"1","(-6750,3900)","0","pure_quanta","I19";
;
LOCATION"C594"
$SEC"1"
CDS_SEC"1"
VALUE"4.7UF"
VOLTAGE"6.3V"
TOLERANCE"20%"
MATERIAL"X6S"
PACK_TYPE"0402"
CDS_LIB"pure_quanta"
PART_NUMBER"CH5471MEB01";
"B"
$PN"2"8;
"A"
$PN"1"1;
%"Q_RES"
"1","(-7875,3275)","0","pure_quanta","I2";
;
LOCATION"R1003"
SEC"1"
VALUE"0"
TOLERANCE"5%"
MATERIAL"EMPTY"
WATTAGE"1/16W"
PACK_TYPE"0402LF"
SEC_TYPE"0402LF"
CDS_LIB"pure_quanta"
PART_NUMBER"CS00002JB13";
"B"
$PN"2"1;
"A"
$PN"1"10;
%"Q_CAP"
"1","(-6525,3900)","0","pure_quanta","I20";
;
LOCATION"C597"
$SEC"1"
CDS_SEC"1"
VOLTAGE"4V"
MATERIAL"X6S"
PACK_TYPE"0201"
TOLERANCE"20%"
VALUE"1UF"
CDS_LIB"pure_quanta"
PART_NUMBER"CH-10KMEE00";
"B"
$PN"2"8;
"A"
$PN"1"1;
%"Q_CAP"
"1","(-6325,3900)","0","pure_quanta","I21";
;
LOCATION"C599"
$SEC"1"
CDS_SEC"1"
MATERIAL"X6S"
PACK_TYPE"0201"
VALUE"1UF"
VOLTAGE"4V"
TOLERANCE"20%"
CDS_LIB"pure_quanta"
PART_NUMBER"CH-10KMEE00";
"B"
$PN"2"8;
"A"
$PN"1"1;
%"Q_CAP"
"1","(-6725,4700)","0","pure_quanta","I22";
;
LOCATION"C591"
$SEC"1"
CDS_SEC"1"
PACK_TYPE"C0402"
MATERIAL"X6S"
TOLERANCE"20%"
VOLTAGE"6.3V"
VALUE"10UF"
CDS_LIB"pure_quanta"
PART_NUMBER"CH6101MEB01";
"B"
$PN"2"7;
"A"
$PN"1"6;
%"UNIVERSAL_GND"
"1","(-6550,4425)","0","pure_quanta_power","I23";
;
CDS_LIB"pure_quanta_power"
HDL_POWER"GND";
"A"7;
%"Q_CAP"
"1","(-6475,4700)","0","pure_quanta","I24";
;
LOCATION"C596"
$SEC"1"
CDS_SEC"1"
VOLTAGE"6.3V"
TOLERANCE"20%"
MATERIAL"X6S"
VALUE"4.7UF"
PACK_TYPE"0402"
CDS_LIB"pure_quanta"
PART_NUMBER"CH5471MEB01";
"B"
$PN"2"7;
"A"
$PN"1"6;
%"Q_CAP"
"1","(-6100,3900)","0","pure_quanta","I25";
;
LOCATION"C600"
$SEC"1"
CDS_SEC"1"
TOLERANCE"10%"
VALUE"0.1UF"
MATERIAL"X7S"
VOLTAGE"10V"
PACK_TYPE"C0201"
CDS_LIB"pure_quanta"
PART_NUMBER"CH4102K6E00";
"B"
$PN"2"8;
"A"
$PN"1"1;
%"Q_CAP"
"1","(-5850,3900)","0","pure_quanta","I26";
;
LOCATION"C602"
$SEC"1"
CDS_SEC"1"
VALUE"0.1UF"
VOLTAGE"10V"
TOLERANCE"10%"
PACK_TYPE"C0201"
MATERIAL"X7S"
CDS_LIB"pure_quanta"
PART_NUMBER"CH4102K6E00";
"B"
$PN"2"8;
"A"
$PN"1"1;
%"Q_CAP"
"1","(-5600,3900)","0","pure_quanta","I27";
;
LOCATION"C603"
$SEC"1"
CDS_SEC"1"
PACK_TYPE"C0201"
MATERIAL"X7S"
TOLERANCE"10%"
VOLTAGE"10V"
VALUE"0.1UF"
CDS_LIB"pure_quanta"
PART_NUMBER"CH4102K6E00";
"B"
$PN"2"8;
"A"
$PN"1"1;
%"Q_CAP"
"1","(-5325,3900)","0","pure_quanta","I28";
;
LOCATION"C606"
$SEC"1"
CDS_SEC"1"
PACK_TYPE"C0201"
TOLERANCE"10%"
VOLTAGE"10V"
VALUE"0.1UF"
MATERIAL"X7S"
CDS_LIB"pure_quanta"
PART_NUMBER"CH4102K6E00";
"B"
$PN"2"8;
"A"
$PN"1"1;
%"VCC_CORE"
"1","(-4475,5675)","0","pure_quanta_power","I29";
;
HDL_POWER"P0V9_CPU0_RT_2D"
CDS_LIB"pure_quanta_power";
"A"4;
%"VCC_CORE"
"1","(-3325,1375)","0","pure_quanta_power","I30";
;
HDL_POWER"P0V9_CPU0_RT1_2A_2D"
CDS_LIB"pure_quanta_power";
"A"13;
%"UNIVERSAL_GND"
"1","(-2500,525)","0","pure_quanta_power","I31";
;
CDS_LIB"pure_quanta_power"
HDL_POWER"GND";
"A"12;
%"Q_CAP"
"1","(-3200,850)","0","pure_quanta","I32";
;
LOCATION"C617"
$SEC"1"
CDS_SEC"1"
PACK_TYPE"C0201"
MATERIAL"X7S"
VALUE"0.1UF"
TOLERANCE"10%"
VOLTAGE"10V"
CDS_LIB"pure_quanta"
PART_NUMBER"CH4102K6E00";
"B"
$PN"2"12;
"A"
$PN"1"13;
%"Q_CAP"
"1","(-2650,850)","0","pure_quanta","I34";
;
LOCATION"C623"
$SEC"1"
CDS_SEC"1"
MATERIAL"X7S"
TOLERANCE"10%"
PACK_TYPE"C0201"
VALUE"0.1UF"
VOLTAGE"10V"
CDS_LIB"pure_quanta"
PART_NUMBER"CH4102K6E00";
"B"
$PN"2"12;
"A"
$PN"1"13;
%"Q_RES"
"1","(-4100,2200)","0","pure_quanta","I36";
;
LOCATION"R1011"
$SEC"1"
CDS_SEC"1"
MATERIAL"CHIP"
TOLERANCE"5%"
WATTAGE"1/4W"
VALUE"0"
PACK_TYPE"0603LF"
CDS_LIB"pure_quanta"
PART_NUMBER"CS00006J900";
"B"
$PN"2"2;
"A"
$PN"1"13;
%"Q_CAP"
"1","(-3375,1950)","0","pure_quanta","I37";
;
LOCATION"C662"
$SEC"1"
CDS_SEC"1"
PACK_TYPE"C0201"
MATERIAL"X7S"
TOLERANCE"10%"
VOLTAGE"10V"
VALUE"0.1UF"
CDS_LIB"pure_quanta"
PART_NUMBER"CH4102K6E00";
"B"
$PN"2"9;
"A"
$PN"1"2;
%"Q_CAP"
"1","(-3650,2650)","0","pure_quanta","I38";
;
LOCATION"C609"
$SEC"1"
CDS_SEC"1"
PACK_TYPE"0201"
VALUE"1UF"
MATERIAL"X6S"
TOLERANCE"20%"
VOLTAGE"4V"
CDS_LIB"pure_quanta"
PART_NUMBER"CH-10KMEE00";
"B"
$PN"2"3;
"A"
$PN"1"2;
%"Q_CAP"
"1","(-3425,2650)","0","pure_quanta","I39";
;
LOCATION"C618"
$SEC"1"
CDS_SEC"1"
PACK_TYPE"0201"
VOLTAGE"4V"
VALUE"1UF"
MATERIAL"X6S"
TOLERANCE"20%"
CDS_LIB"pure_quanta"
PART_NUMBER"CH-10KMEE00";
"B"
$PN"2"3;
"A"
$PN"1"2;
%"Q_RES"
"1","(-7875,3475)","0","pure_quanta","I4";
;
LOCATION"R1002"
SEC"1"
PACK_TYPE"0402LF"
TOLERANCE"5%"
VALUE"0"
MATERIAL"EMPTY"
WATTAGE"1/16W"
CDS_LIB"pure_quanta"
SEC_TYPE"0402LF"
PART_NUMBER"CS00002JB13";
"B"
$PN"2"1;
"A"
$PN"1"10;
%"Q_CAP"
"1","(-3650,3275)","0","pure_quanta","I40";
;
LOCATION"C626"
$SEC"1"
CDS_SEC"1"
VOLTAGE"6.3V"
VALUE"10UF"
PACK_TYPE"C0402"
TOLERANCE"20%"
MATERIAL"X6S"
CDS_LIB"pure_quanta"
PART_NUMBER"CH6101MEB01";
"B"
$PN"2"3;
"A"
$PN"1"2;
%"Q_CAP"
"1","(-3425,3275)","0","pure_quanta","I41";
;
LOCATION"C645"
$SEC"1"
CDS_SEC"1"
TOLERANCE"20%"
VOLTAGE"6.3V"
MATERIAL"X6S"
PACK_TYPE"C0402"
VALUE"10UF"
CDS_LIB"pure_quanta"
PART_NUMBER"CH6101MEB01";
"B"
$PN"2"3;
"A"
$PN"1"2;
%"Q_CAP"
"1","(-3075,1950)","0","pure_quanta","I42";
;
LOCATION"C616"
$SEC"1"
CDS_SEC"1"
PACK_TYPE"C0201"
MATERIAL"X7S"
TOLERANCE"10%"
VOLTAGE"10V"
VALUE"0.1UF"
CDS_LIB"pure_quanta"
PART_NUMBER"CH4102K6E00";
"B"
$PN"2"9;
"A"
$PN"1"2;
%"Q_CAP"
"1","(-2850,1950)","0","pure_quanta","I43";
;
LOCATION"C657"
$SEC"1"
CDS_SEC"1"
VALUE"0.1UF"
VOLTAGE"10V"
TOLERANCE"10%"
MATERIAL"X7S"
PACK_TYPE"C0201"
CDS_LIB"pure_quanta"
PART_NUMBER"CH4102K6E00";
"B"
$PN"2"9;
"A"
$PN"1"2;
%"Q_CAP"
"1","(-3175,2650)","0","pure_quanta","I44";
;
LOCATION"C607"
$SEC"1"
CDS_SEC"1"
MATERIAL"X6S"
VALUE"1UF"
PACK_TYPE"0201"
TOLERANCE"20%"
VOLTAGE"4V"
CDS_LIB"pure_quanta"
PART_NUMBER"CH-10KMEE00";
"B"
$PN"2"3;
"A"
$PN"1"2;
%"Q_CAP"
"1","(-2950,2650)","0","pure_quanta","I45";
;
LOCATION"C643"
$SEC"1"
CDS_SEC"1"
VALUE"1UF"
VOLTAGE"4V"
TOLERANCE"20%"
PACK_TYPE"0201"
MATERIAL"X6S"
CDS_LIB"pure_quanta"
PART_NUMBER"CH-10KMEE00";
"B"
$PN"2"3;
"A"
$PN"1"2;
%"Q_CAP"
"1","(-2600,1950)","0","pure_quanta","I46";
;
LOCATION"C635"
$SEC"1"
CDS_SEC"1"
MATERIAL"X7S"
TOLERANCE"10%"
VOLTAGE"10V"
PACK_TYPE"C0201"
VALUE"0.1UF"
CDS_LIB"pure_quanta"
PART_NUMBER"CH4102K6E00";
"B"
$PN"2"9;
"A"
$PN"1"2;
%"Q_CAP"
"1","(-2350,1950)","0","pure_quanta","I47";
;
LOCATION"C627"
$SEC"1"
CDS_SEC"1"
VALUE"0.1UF"
PACK_TYPE"C0201"
TOLERANCE"10%"
MATERIAL"X7S"
VOLTAGE"10V"
CDS_LIB"pure_quanta"
PART_NUMBER"CH4102K6E00";
"B"
$PN"2"9;
"A"
$PN"1"2;
%"Q_CAP"
"1","(-2700,2650)","0","pure_quanta","I48";
;
LOCATION"C647"
$SEC"1"
CDS_SEC"1"
VOLTAGE"4V"
PACK_TYPE"0201"
VALUE"1UF"
MATERIAL"X6S"
TOLERANCE"20%"
CDS_LIB"pure_quanta"
PART_NUMBER"CH-10KMEE00";
"B"
$PN"2"3;
"A"
$PN"1"2;
%"Q_CAP"
"1","(-2250,2625)","0","pure_quanta","I49";
;
LOCATION"C654"
$SEC"1"
CDS_SEC"1"
TOLERANCE"20%"
MATERIAL"X6S"
VOLTAGE"4V"
VALUE"1UF"
PACK_TYPE"0201"
CDS_LIB"pure_quanta"
PART_NUMBER"CH-10KMEE00";
"B"
$PN"2"3;
"A"
$PN"1"2;
%"Q_CAP"
"1","(-6950,2825)","0","pure_quanta","I5";
;
LOCATION"C598"
$SEC"1"
CDS_SEC"1"
MATERIAL"X6S"
PACK_TYPE"0201"
VALUE"1UF"
VOLTAGE"4V"
TOLERANCE"20%"
CDS_LIB"pure_quanta"
PART_NUMBER"CH-10KMEE00";
"B"
$PN"2"11;
"A"
$PN"1"10;
%"Q_CAP"
"1","(-3200,3275)","0","pure_quanta","I50";
;
LOCATION"C644"
$SEC"1"
CDS_SEC"1"
MATERIAL"X6S"
VALUE"4.7UF"
TOLERANCE"20%"
PACK_TYPE"0402"
VOLTAGE"6.3V"
CDS_LIB"pure_quanta"
PART_NUMBER"CH5471MEB01";
"B"
$PN"2"3;
"A"
$PN"1"2;
%"Q_CAP"
"1","(-2975,3275)","0","pure_quanta","I51";
;
LOCATION"C638"
$SEC"1"
CDS_SEC"1"
PACK_TYPE"0402"
MATERIAL"X6S"
TOLERANCE"20%"
VOLTAGE"6.3V"
VALUE"4.7UF"
CDS_LIB"pure_quanta"
PART_NUMBER"CH5471MEB01";
"B"
$PN"2"3;
"A"
$PN"1"2;
%"Q_CAP"
"1","(-2500,3275)","0","pure_quanta","I52";
;
LOCATION"C649"
$SEC"1"
CDS_SEC"1"
MATERIAL"X6S"
VALUE"4.7UF"
TOLERANCE"20%"
VOLTAGE"6.3V"
PACK_TYPE"0402"
CDS_LIB"pure_quanta"
PART_NUMBER"CH5471MEB01";
"B"
$PN"2"3;
"A"
$PN"1"2;
%"Q_CAP"
"1","(-2275,3275)","0","pure_quanta","I53";
;
LOCATION"C653"
$SEC"1"
CDS_SEC"1"
VALUE"1UF"
MATERIAL"X6S"
VOLTAGE"4V"
PACK_TYPE"0201"
TOLERANCE"20%"
CDS_LIB"pure_quanta"
PART_NUMBER"CH-10KMEE00";
"B"
$PN"2"3;
"A"
$PN"1"2;
%"UNIVERSAL_GND"
"1","(-1550,1525)","0","pure_quanta_power","I54";
;
CDS_LIB"pure_quanta_power"
HDL_POWER"GND";
"A"9;
%"Q_CAP"
"1","(-1800,1950)","0","pure_quanta","I55";
;
LOCATION"C631"
$SEC"1"
CDS_SEC"1"
VALUE"0.1UF"
PACK_TYPE"C0201"
TOLERANCE"10%"
MATERIAL"X7S"
VOLTAGE"10V"
CDS_LIB"pure_quanta"
PART_NUMBER"CH4102K6E00";
"B"
$PN"2"9;
"A"
$PN"1"2;
%"Q_CAP"
"1","(-1550,1950)","0","pure_quanta","I58";
;
LOCATION"C650"
$SEC"1"
CDS_SEC"1"
PACK_TYPE"C0201"
VALUE"0.1UF"
VOLTAGE"10V"
MATERIAL"X7S"
TOLERANCE"10%"
CDS_LIB"pure_quanta"
PART_NUMBER"CH4102K6E00";
"B"
$PN"2"9;
"A"
$PN"1"2;
%"Q_CAP"
"1","(-2050,3275)","0","pure_quanta","I59";
;
LOCATION"C620"
$SEC"1"
CDS_SEC"1"
MATERIAL"X6S"
VALUE"1UF"
VOLTAGE"4V"
TOLERANCE"20%"
PACK_TYPE"0201"
CDS_LIB"pure_quanta"
PART_NUMBER"CH-10KMEE00";
"B"
$PN"2"3;
"A"
$PN"1"2;
%"UNIVERSAL_GND"
"1","(-6675,2400)","0","pure_quanta_power","I6";
;
CDS_LIB"pure_quanta_power"
HDL_POWER"GND";
"A"11;
%"Q_CAP"
"1","(-1575,3275)","0","pure_quanta","I61";
;
LOCATION"C613"
$SEC"1"
CDS_SEC"1"
PACK_TYPE"0201"
TOLERANCE"20%"
VOLTAGE"4V"
VALUE"1UF"
MATERIAL"X6S"
CDS_LIB"pure_quanta"
PART_NUMBER"CH-10KMEE00";
"B"
$PN"2"3;
"A"
$PN"1"2;
%"UNIVERSAL_GND"
"1","(-1050,2225)","0","pure_quanta_power","I62";
;
CDS_LIB"pure_quanta_power"
HDL_POWER"GND";
"A"3;
%"Q_INDUCTOR"
"1","(-4000,4175)","0","pure_quanta","I63";
;
LOCATION"L14"
$SEC"1"
CDS_SEC"1"
VALUE"100NH/16A"
PACK_TYPE"SMLF"
MATERIAL"IND"
CDS_LIB"pure_quanta"
NEEDS_NO_SIZE"TRUE"
PART_NUMBER"CV+10G0MZ04";
"1"
$PN"1"4;
"2"
$PN"2"2;
%"Q_CAP"
"1","(-3650,3900)","0","pure_quanta","I64";
;
LOCATION"C625"
$SEC"1"
CDS_SEC"1"
TOLERANCE"20%"
MATERIAL"X6S"
VOLTAGE"4V"
VALUE"100UF"
PACK_TYPE"C0805"
CDS_LIB"pure_quanta"
PART_NUMBER"CH710KMEA01";
"B"
$PN"2"3;
"A"
$PN"1"2;
%"Q_CAP"
"1","(-3425,3900)","0","pure_quanta","I65";
;
LOCATION"C628"
$SEC"1"
CDS_SEC"1"
VOLTAGE"4V"
MATERIAL"X6S"
PACK_TYPE"C0805"
VALUE"100UF"
TOLERANCE"20%"
CDS_LIB"pure_quanta"
PART_NUMBER"CH710KMEA01";
"B"
$PN"2"3;
"A"
$PN"1"2;
%"VCC_CORE"
"1","(-3650,4550)","0","pure_quanta_power","I66";
;
HDL_POWER"P0V9_CPU0_RT1_2A"
CDS_LIB"pure_quanta_power";
"A"2;
%"Q_CAP"
"1","(-3600,5175)","0","pure_quanta","I67";
;
LOCATION"C632"
$SEC"1"
CDS_SEC"1"
TOLERANCE"20%"
PACK_TYPE"C0805"
VOLTAGE"4V"
VALUE"100UF"
MATERIAL"X6S"
CDS_LIB"pure_quanta"
PART_NUMBER"CH710KMEA01";
"B"
$PN"2"5;
"A"
$PN"1"4;
%"Q_CAP"
"1","(-3325,5175)","0","pure_quanta","I68";
;
LOCATION"C636"
$SEC"1"
CDS_SEC"1"
VALUE"22UF"
PACK_TYPE"C0402"
VOLTAGE"4V"
MATERIAL"X6S"
TOLERANCE"20%"
CDS_LIB"pure_quanta"
PART_NUMBER"CH622KMEB02";
"B"
$PN"2"5;
"A"
$PN"1"4;
%"Q_CAP"
"1","(-3200,3900)","0","pure_quanta","I69";
;
LOCATION"C633"
$SEC"1"
CDS_SEC"1"
VALUE"100UF"
VOLTAGE"4V"
TOLERANCE"20%"
MATERIAL"X6S"
PACK_TYPE"C0805"
CDS_LIB"pure_quanta"
PART_NUMBER"CH710KMEA01";
"B"
$PN"2"3;
"A"
$PN"1"2;
%"Q_CAP"
"1","(-6675,2800)","0","pure_quanta","I7";
;
LOCATION"C601"
$SEC"1"
CDS_SEC"1"
VOLTAGE"10V"
TOLERANCE"10%"
VALUE"0.1UF"
MATERIAL"X7S"
PACK_TYPE"C0201"
CDS_LIB"pure_quanta"
PART_NUMBER"CH4102K6E00";
"B"
$PN"2"11;
"A"
$PN"1"10;
%"Q_CAP"
"1","(-2975,3900)","0","pure_quanta","I70";
;
LOCATION"C637"
$SEC"1"
CDS_SEC"1"
VOLTAGE"4V"
MATERIAL"X6S"
TOLERANCE"20%"
PACK_TYPE"C0805"
VALUE"100UF"
CDS_LIB"pure_quanta"
PART_NUMBER"CH710KMEA01";
"B"
$PN"2"3;
"A"
$PN"1"2;
%"Q_CAP"
"1","(-2725,3900)","0","pure_quanta","I71";
;
LOCATION"C634"
$SEC"1"
CDS_SEC"1"
TOLERANCE"20%"
VOLTAGE"4V"
MATERIAL"X6S"
VALUE"22UF"
PACK_TYPE"C0402"
CDS_LIB"pure_quanta"
PART_NUMBER"CH622KMEB02";
"B"
$PN"2"3;
"A"
$PN"1"2;
%"Q_CAP"
"1","(-2500,3900)","0","pure_quanta","I72";
;
LOCATION"C663"
$SEC"1"
CDS_SEC"1"
TOLERANCE"20%"
MATERIAL"X6S"
VOLTAGE"4V"
PACK_TYPE"C0402"
VALUE"22UF"
CDS_LIB"pure_quanta"
PART_NUMBER"CH622KMEB02";
"B"
$PN"2"3;
"A"
$PN"1"2;
%"Q_CAP"
"1","(-2275,3900)","0","pure_quanta","I73";
;
LOCATION"C630"
$SEC"1"
CDS_SEC"1"
PACK_TYPE"C0402"
VOLTAGE"4V"
MATERIAL"X6S"
VALUE"22UF"
TOLERANCE"20%"
CDS_LIB"pure_quanta"
PART_NUMBER"CH622KMEB02";
"B"
$PN"2"3;
"A"
$PN"1"2;
%"Q_CAP"
"1","(-3000,5150)","0","pure_quanta","I74";
;
LOCATION"C646"
$SEC"1"
CDS_SEC"1"
VALUE"10UF"
MATERIAL"X6S"
PACK_TYPE"C0402"
VOLTAGE"6.3V"
TOLERANCE"20%"
CDS_LIB"pure_quanta"
PART_NUMBER"CH6101MEB01";
"B"
$PN"2"5;
"A"
$PN"1"4;
%"Q_CAP"
"1","(-2700,5150)","0","pure_quanta","I75";
;
LOCATION"C651"
$SEC"1"
CDS_SEC"1"
VOLTAGE"6.3V"
VALUE"4.7UF"
MATERIAL"X6S"
PACK_TYPE"0402"
TOLERANCE"20%"
CDS_LIB"pure_quanta"
PART_NUMBER"CH5471MEB01";
"B"
$PN"2"5;
"A"
$PN"1"4;
%"Q_CAP"
"1","(-2400,5150)","0","pure_quanta","I76";
;
LOCATION"C655"
$SEC"1"
CDS_SEC"1"
MATERIAL"X6S"
PACK_TYPE"0201"
VOLTAGE"4V"
VALUE"1UF"
TOLERANCE"20%"
CDS_LIB"pure_quanta"
PART_NUMBER"CH-10KMEE00";
"B"
$PN"2"5;
"A"
$PN"1"4;
%"Q_CAP"
"1","(-2050,3900)","0","pure_quanta","I77";
;
LOCATION"C656"
$SEC"1"
CDS_SEC"1"
MATERIAL"X6S"
TOLERANCE"20%"
VALUE"22UF"
VOLTAGE"4V"
PACK_TYPE"C0402"
CDS_LIB"pure_quanta"
PART_NUMBER"CH622KMEB02";
"B"
$PN"2"3;
"A"
$PN"1"2;
%"Q_CAP"
"1","(-1750,3900)","0","pure_quanta","I78";
;
LOCATION"C661"
$SEC"1"
CDS_SEC"1"
VOLTAGE"6.3V"
PACK_TYPE"C0402"
TOLERANCE"20%"
MATERIAL"X6S"
VALUE"10UF"
CDS_LIB"pure_quanta"
PART_NUMBER"CH6101MEB01";
"B"
$PN"2"3;
"A"
$PN"1"2;
%"Q_CAP"
"1","(-1450,3900)","0","pure_quanta","I79";
;
LOCATION"C648"
$SEC"1"
CDS_SEC"1"
VALUE"10UF"
TOLERANCE"20%"
MATERIAL"X6S"
VOLTAGE"6.3V"
PACK_TYPE"C0402"
CDS_LIB"pure_quanta"
PART_NUMBER"CH6101MEB01";
"B"
$PN"2"3;
"A"
$PN"1"2;
%"P1V0"
"1","(-7075,3200)","0","pure_quanta_power","I8";
;
HDL_POWER"P1V8_CPU0_RT1_1A_1D"
CDS_LIB"pure_quanta_power";
"A"10;
%"UNIVERSAL_GND"
"1","(-1375,4725)","0","pure_quanta_power","I80";
;
CDS_LIB"pure_quanta_power"
HDL_POWER"GND";
"A"5;
%"Q_CAP"
"1","(-2100,5125)","0","pure_quanta","I81";
;
LOCATION"C608"
$SEC"1"
CDS_SEC"1"
TOLERANCE"10%"
MATERIAL"X7S"
VALUE"0.1UF"
VOLTAGE"10V"
PACK_TYPE"C0201"
CDS_LIB"pure_quanta"
PART_NUMBER"CH4102K6E00";
"B"
$PN"2"5;
"A"
$PN"1"4;
%"Q_CAP"
"1","(-1825,5125)","0","pure_quanta","I82";
;
LOCATION"C610"
$SEC"1"
CDS_SEC"1"
TOLERANCE"10%"
MATERIAL"X7S"
VALUE"0.1UF"
VOLTAGE"10V"
PACK_TYPE"C0201"
CDS_LIB"pure_quanta"
PART_NUMBER"CH4102K6E00";
"B"
$PN"2"5;
"A"
$PN"1"4;
%"Q_CAP"
"1","(-1575,5125)","0","pure_quanta","I83";
;
LOCATION"C615"
$SEC"1"
CDS_SEC"1"
VOLTAGE"10V"
VALUE"0.1UF"
PACK_TYPE"C0201"
TOLERANCE"10%"
MATERIAL"X7S"
CDS_LIB"pure_quanta"
PART_NUMBER"CH4102K6E00";
"B"
$PN"2"5;
"A"
$PN"1"4;
%"Q_CAP"
"1","(-1300,5125)","0","pure_quanta","I84";
;
LOCATION"C619"
$SEC"1"
CDS_SEC"1"
VOLTAGE"10V"
MATERIAL"X7S"
PACK_TYPE"C0201"
VALUE"0.1UF"
TOLERANCE"10%"
CDS_LIB"pure_quanta"
PART_NUMBER"CH4102K6E00";
"B"
$PN"2"5;
"A"
$PN"1"4;
%"Q_CAP"
"1","(-2075,1950)","0","pure_quanta","I85";
;
LOCATION"C614"
$SEC"1"
CDS_SEC"1"
VALUE"0.1UF"
PACK_TYPE"C0201"
TOLERANCE"10%"
MATERIAL"X7S"
VOLTAGE"10V"
CDS_LIB"pure_quanta"
PART_NUMBER"CH4102K6E00";
"B"
$PN"2"9;
"A"
$PN"1"2;
%"Q_CAP"
"1","(-2475,2625)","0","pure_quanta","I86";
;
LOCATION"C622"
$SEC"1"
CDS_SEC"1"
PACK_TYPE"0201"
VALUE"1UF"
VOLTAGE"4V"
TOLERANCE"20%"
MATERIAL"X6S"
CDS_LIB"pure_quanta"
PART_NUMBER"CH-10KMEE00";
"B"
$PN"2"3;
"A"
$PN"1"2;
%"Q_CAP"
"1","(-2725,3275)","0","pure_quanta","I87";
;
LOCATION"C652"
$SEC"1"
CDS_SEC"1"
VOLTAGE"6.3V"
PACK_TYPE"0402"
VALUE"4.7UF"
TOLERANCE"20%"
MATERIAL"X6S"
CDS_LIB"pure_quanta"
PART_NUMBER"CH5471MEB01";
"B"
$PN"2"3;
"A"
$PN"1"2;
%"Q_INDUCTOR"
"1","(-8400,3825)","3","pure_quanta","I88";
;
LOCATION"L28"
$SEC"1"
CDS_SEC"1"
MATERIAL"IND"
PACK_TYPE"SMLF"
VALUE"BLM15PD121SN1D/1300MA"
CDS_LIB"pure_quanta"
NEEDS_NO_SIZE"TRUE"
PART_NUMBER"CX5PD121000";
"1"
$PN"1"6;
"2"
$PN"2"10;
%"Q_RES"
"2","(-8275,3800)","0","pure_quanta","I89";
;
LOCATION"R1008"
$SEC"1"
CDS_SEC"1"
TOLERANCE"5%"
VALUE"0"
WATTAGE"1/16W"
MATERIAL"EMPTY"
PACK_TYPE"0402LF"
CDS_LIB"pure_quanta"
PART_NUMBER"CS00002JB13";
"A"
$PN"1"6;
"B"
$PN"2"10;
%"UNIVERSAL_GND"
"1","(-6325,3575)","0","pure_quanta_power","I9";
;
CDS_LIB"pure_quanta_power"
HDL_POWER"GND";
"A"8;
%"Q_CAP"
"1","(-2950,850)","0","pure_quanta","I90";
;
LOCATION"C621"
$SEC"1"
CDS_SEC"1"
TOLERANCE"20%"
MATERIAL"X6S"
PACK_TYPE"0201"
VOLTAGE"4V"
VALUE"1UF"
CDS_LIB"pure_quanta"
PART_NUMBER"CH-10KMEE00";
"B"
$PN"2"12;
"A"
$PN"1"13;
%"Q_CAP"
"1","(-2400,850)","0","pure_quanta","I91";
;
LOCATION"C624"
$SEC"1"
CDS_SEC"1"
TOLERANCE"20%"
MATERIAL"X6S"
PACK_TYPE"0201"
VOLTAGE"4V"
VALUE"1UF"
CDS_LIB"pure_quanta"
PART_NUMBER"CH-10KMEE00";
"B"
$PN"2"12;
"A"
$PN"1"13;
%"Q_CAP"
"1","(-1975,2625)","0","pure_quanta","I92";
;
LOCATION"C658"
$SEC"1"
CDS_SEC"1"
TOLERANCE"10%"
VOLTAGE"10V"
PACK_TYPE"C0201"
MATERIAL"X7S"
VALUE"0.1UF"
CDS_LIB"pure_quanta"
PART_NUMBER"CH4102K6E00";
"B"
$PN"2"3;
"A"
$PN"1"2;
%"Q_CAP"
"1","(-1700,2625)","0","pure_quanta","I93";
;
LOCATION"C659"
$SEC"1"
CDS_SEC"1"
VOLTAGE"10V"
VALUE"0.1UF"
PACK_TYPE"C0201"
MATERIAL"X7S"
TOLERANCE"10%"
CDS_LIB"pure_quanta"
PART_NUMBER"CH4102K6E00";
"B"
$PN"2"3;
"A"
$PN"1"2;
%"Q_CAP"
"1","(-1825,3275)","0","pure_quanta","I94";
;
LOCATION"C660"
$SEC"1"
CDS_SEC"1"
VALUE"1UF"
VOLTAGE"4V"
TOLERANCE"20%"
MATERIAL"X6S"
PACK_TYPE"0201"
CDS_LIB"pure_quanta"
PART_NUMBER"CH-10KMEE00";
"B"
$PN"2"3;
"A"
$PN"1"2;
%"Q_CAPP"
"1","(-1275,1950)","0","pure_quanta","I95";
;
LOCATION"C7011"
$SEC"1"
CDS_SEC"1"
MATERIAL"SPCAP"
VOLTAGE"2.5V"
PACK_TYPE"SMLF"
TOLERANCE"20%"
VALUE"470UF"
CDS_LIB"pure_quanta"
PART_NUMBER"CH747LM8818";
"A"
$PN"1"2;
"B"
$PN"2"9;
%"Q_CAPP"
"1","(-975,1950)","0","pure_quanta","I96";
;
LOCATION"C7012"
$SEC"1"
CDS_SEC"1"
PACK_TYPE"SMLF"
TOLERANCE"20%"
VOLTAGE"2.5V"
MATERIAL"SPCAP"
VALUE"470UF"
CDS_LIB"pure_quanta"
PART_NUMBER"CH747LM8818";
"A"
$PN"1"2;
"B"
$PN"2"9;
%"Q_CAP"
"1","(-675,1950)","0","pure_quanta","I97";
;
LOCATION"C7013"
$SEC"1"
CDS_SEC"1"
TOLERANCE"20%"
VALUE"100UF"
VOLTAGE"4V"
MATERIAL"X6S"
PACK_TYPE"C0805"
CDS_LIB"pure_quanta"
PART_NUMBER"CH710KMEA01";
"B"
$PN"2"9;
"A"
$PN"1"2;
END.
